(kicad_pcb
	(version 20260206)
	(generator "pcbnew")
	(generator_version "10.0")
	(general
		(thickness 1.6)
		(legacy_teardrops no)
	)
	(paper "A4")
	(title_block
		(title "03242023_DA0F0TMBIJ0_F0T_Motherboard_J_brd_V01_OCP.brd")
		(comment 1 "Grand Teton / footprint 3039 of 6105 (U2), pads 427-533 of 4677")
	)
	(layers
		(0 "F.Cu" signal "TOP")
		(4 "In1.Cu" signal "GND")
		(6 "In2.Cu" signal "IN1")
		(8 "In3.Cu" signal "GND1")
		(10 "In4.Cu" signal "IN2")
		(12 "In5.Cu" signal "GND2")
		(14 "In6.Cu" signal "IN3")
		(16 "In7.Cu" signal "GND3")
		(18 "In8.Cu" signal "VCC")
		(20 "In9.Cu" signal "VCC1")
		(22 "In10.Cu" signal "GND4")
		(24 "In11.Cu" signal "IN4")
		(26 "In12.Cu" signal "GND5")
		(28 "In13.Cu" signal "IN5")
		(30 "In14.Cu" signal "GND6")
		(32 "In15.Cu" signal "IN6")
		(34 "In16.Cu" signal "GND7")
		(2 "B.Cu" signal "BOTTOM")
		(9 "F.Adhes" user "F.Adhesive")
		(11 "B.Adhes" user "B.Adhesive")
		(13 "F.Paste" user "Package Geometry/Pastemask Top")
		(15 "B.Paste" user "Package Geometry/Pastemask Bottom")
		(5 "F.SilkS" user "Ref Des/Silkscreen Top")
		(7 "B.SilkS" user "Ref Des/Silkscreen Bottom")
		(1 "F.Mask" user "Board Geometry/Soldermask Top")
		(3 "B.Mask" user "Board Geometry/Soldermask Bottom")
		(17 "Dwgs.User" user "User.Drawings")
		(19 "Cmts.User" user "User.Comments")
		(21 "Eco1.User" user "User.Eco1")
		(23 "Eco2.User" user "User.Eco2")
		(25 "Edge.Cuts" user "Board Geometry/Outline")
		(27 "Margin" user)
		(31 "F.CrtYd" user "Package Geometry/Place Bound Top")
		(29 "B.CrtYd" user "Package Geometry/Place Bound Bottom")
		(35 "F.Fab" user "Ref Des/Assembly Top")
		(33 "B.Fab" user "Ref Des/Assembly Bottom")
	)
	(footprint ""
		(layer "F.Cu")
		(at 359.870248 -251.76988 90)
		(property "Reference" "U2"
			(at -74.416158 -44.488608 0)
			(unlocked yes)
			(layer "F.SilkS")
			(effects
				(font
					(size 1.6002 1.1938)
					(thickness 0.1524)
				)
				(justify left)
			)
		)
		(property "Value" ""
			(at 0 0 90)
			(layer "F.Fab")
			(effects
				(font
					(size 1.27 1.27)
				)
			)
		)
		(duplicate_pad_numbers_are_jumpers no)
		(pad "AJ82" smd circle
			(at 30.100016 -13.806932 270)
			(size 0.4318 0.4318)
			(layers "F.Cu" "F.Mask" "F.Paste")
			(net "UPI_CPU1_CPU0_P2P2_DN<12>")
		)
		(pad "AJ84" smd circle
			(at 31.727902 -13.806932 270)
			(size 0.4318 0.4318)
			(layers "F.Cu" "F.Mask" "F.Paste")
			(net "GND")
		)
		(pad "AJ86" smd circle
			(at 33.355534 -13.806932 270)
			(size 0.4318 0.4318)
			(layers "F.Cu" "F.Mask" "F.Paste")
			(net "P5E_CPU0_PE4_TX_DN<9>")
		)
		(pad "AJ88" smd circle
			(at 34.98342 -13.806932 270)
			(size 0.4318 0.4318)
			(layers "F.Cu" "F.Mask" "F.Paste")
			(net "GND")
		)
		(pad "AJ90" smd circle
			(at 36.611306 -13.806932 270)
			(size 0.4318 0.4318)
			(layers "F.Cu" "F.Mask" "F.Paste")
			(net "P5E_CPU0_PE4_RX_DP<9>")
		)
		(pad "AK2" smd circle
			(at -36.611306 -13.447268 270)
			(size 0.4318 0.4318)
			(layers "F.Cu" "F.Mask" "F.Paste")
			(net "UPI_CPU0_CPU1_P0P1_DN<10>")
		)
		(pad "AK4" smd circle
			(at -34.98342 -13.447268 270)
			(size 0.4318 0.4318)
			(layers "F.Cu" "F.Mask" "F.Paste")
			(net "GND")
		)
		(pad "AK6" smd circle
			(at -33.355534 -13.447268 270)
			(size 0.4318 0.4318)
			(layers "F.Cu" "F.Mask" "F.Paste")
			(net "UPI_CPU1_CPU0_P1P0_DP<10>")
		)
		(pad "AK8" smd circle
			(at -31.727902 -13.447268 270)
			(size 0.4318 0.4318)
			(layers "F.Cu" "F.Mask" "F.Paste")
			(net "GND")
		)
		(pad "AK10" smd circle
			(at -30.100016 -13.447268 270)
			(size 0.4318 0.4318)
			(layers "F.Cu" "F.Mask" "F.Paste")
			(net "P5E_CPU0_PE0_RX_DN<10>")
		)
		(pad "AK12" smd circle
			(at -28.472384 -13.447268 270)
			(size 0.4318 0.4318)
			(layers "F.Cu" "F.Mask" "F.Paste")
			(net "GND")
		)
		(pad "AK14" smd circle
			(at -26.844498 -13.447268 270)
			(size 0.4318 0.4318)
			(layers "F.Cu" "F.Mask" "F.Paste")
			(net "P5E_CPU0_PE0_TX_DN<9>")
		)
		(pad "AK16" smd circle
			(at -25.216612 -13.447268 270)
			(size 0.4318 0.4318)
			(layers "F.Cu" "F.Mask" "F.Paste")
			(net "GND")
		)
		(pad "AK18" smd circle
			(at -23.58898 -13.447268 270)
			(size 0.4318 0.4318)
			(layers "F.Cu" "F.Mask" "F.Paste")
			(net "GND")
		)
		(pad "AK20" smd circle
			(at -21.961094 -13.447268 270)
			(size 0.4318 0.4318)
			(layers "F.Cu" "F.Mask" "F.Paste")
			(net "M_D_CPU0_SB_DQ<28>")
		)
		(pad "AK22" smd circle
			(at -20.333462 -13.447268 270)
			(size 0.4318 0.4318)
			(layers "F.Cu" "F.Mask" "F.Paste")
			(net "M_D_CPU0_SB_DQ<25>")
		)
		(pad "AK24" smd circle
			(at -18.705576 -13.447268 270)
			(size 0.4318 0.4318)
			(layers "F.Cu" "F.Mask" "F.Paste")
			(net "GND")
		)
		(pad "AK26" smd circle
			(at -17.07769 -13.447268 270)
			(size 0.4318 0.4318)
			(layers "F.Cu" "F.Mask" "F.Paste")
			(net "M_D_CPU0_SB_DQ<12>")
		)
		(pad "AK28" smd circle
			(at -15.450058 -13.447268 270)
			(size 0.4318 0.4318)
			(layers "F.Cu" "F.Mask" "F.Paste")
			(net "M_D_CPU0_SB_DQ<9>")
		)
		(pad "AK30" smd circle
			(at -13.822426 -13.447268 270)
			(size 0.4318 0.4318)
			(layers "F.Cu" "F.Mask" "F.Paste")
			(net "GND")
		)
		(pad "AK32" smd circle
			(at -12.19454 -13.447268 270)
			(size 0.4318 0.4318)
			(layers "F.Cu" "F.Mask" "F.Paste")
			(net "M_D_CPU0_SB_DQ<4>")
		)
		(pad "AK34" smd circle
			(at -10.566654 -13.447268 270)
			(size 0.4318 0.4318)
			(layers "F.Cu" "F.Mask" "F.Paste")
			(net "M_D_CPU0_SB_DQ<1>")
		)
		(pad "AK36" smd circle
			(at -8.939022 -13.447268 270)
			(size 0.4318 0.4318)
			(layers "F.Cu" "F.Mask" "F.Paste")
			(net "GND")
		)
		(pad "AK38" smd circle
			(at -7.311136 -13.447268 270)
			(size 0.4318 0.4318)
			(layers "F.Cu" "F.Mask" "F.Paste")
			(net "M_D_CPU0_SB_CB<0>")
		)
		(pad "AK40" smd circle
			(at -5.68325 -13.447268 270)
			(size 0.4318 0.4318)
			(layers "F.Cu" "F.Mask" "F.Paste")
			(net "M_D_CPU0_SB_CB<5>")
		)
		(pad "AK42" smd circle
			(at -4.055618 -13.447268 270)
			(size 0.4318 0.4318)
			(layers "F.Cu" "F.Mask" "F.Paste")
			(net "GND")
		)
		(pad "AK44" smd circle
			(at -2.427732 -13.447268 270)
			(size 0.4318 0.4318)
			(layers "F.Cu" "F.Mask" "F.Paste")
			(net "M_D_CPU0_SB_CA<0>")
		)
		(pad "AK47" smd circle
			(at 1.613916 -13.337286 270)
			(size 0.4318 0.4318)
			(layers "F.Cu" "F.Mask" "F.Paste")
			(net "M_B_CPU0_SA_RSP<1>")
		)
		(pad "AK49" smd circle
			(at 3.241802 -13.337286 270)
			(size 0.4318 0.4318)
			(layers "F.Cu" "F.Mask" "F.Paste")
			(net "GND")
		)
		(pad "AK51" smd circle
			(at 4.869434 -13.337286 270)
			(size 0.4318 0.4318)
			(layers "F.Cu" "F.Mask" "F.Paste")
			(net "M_D_CPU0_SA_CA<2>")
		)
		(pad "AK53" smd circle
			(at 6.49732 -13.337286 270)
			(size 0.4318 0.4318)
			(layers "F.Cu" "F.Mask" "F.Paste")
			(net "M_D_CPU0_SA_CS_N<1>")
		)
		(pad "AK55" smd circle
			(at 8.124952 -13.337286 270)
			(size 0.4318 0.4318)
			(layers "F.Cu" "F.Mask" "F.Paste")
			(net "GND")
		)
		(pad "AK57" smd circle
			(at 9.752838 -13.337286 270)
			(size 0.4318 0.4318)
			(layers "F.Cu" "F.Mask" "F.Paste")
			(net "M_D_CPU0_SA_CB<4>")
		)
		(pad "AK59" smd circle
			(at 11.380724 -13.337286 270)
			(size 0.4318 0.4318)
			(layers "F.Cu" "F.Mask" "F.Paste")
			(net "M_D_CPU0_SA_CB<1>")
		)
		(pad "AK61" smd circle
			(at 13.008356 -13.337286 270)
			(size 0.4318 0.4318)
			(layers "F.Cu" "F.Mask" "F.Paste")
			(net "GND")
		)
		(pad "AK63" smd circle
			(at 14.635988 -13.337286 270)
			(size 0.4318 0.4318)
			(layers "F.Cu" "F.Mask" "F.Paste")
			(net "M_D_CPU0_SA_DQ<28>")
		)
		(pad "AK65" smd circle
			(at 16.263874 -13.337286 270)
			(size 0.4318 0.4318)
			(layers "F.Cu" "F.Mask" "F.Paste")
			(net "M_D_CPU0_SA_DQ<25>")
		)
		(pad "AK67" smd circle
			(at 17.89176 -13.337286 270)
			(size 0.4318 0.4318)
			(layers "F.Cu" "F.Mask" "F.Paste")
			(net "GND")
		)
		(pad "AK69" smd circle
			(at 19.519392 -13.337286 270)
			(size 0.4318 0.4318)
			(layers "F.Cu" "F.Mask" "F.Paste")
			(net "M_D_CPU0_SA_DQ<20>")
		)
		(pad "AK71" smd circle
			(at 21.147278 -13.337286 270)
			(size 0.4318 0.4318)
			(layers "F.Cu" "F.Mask" "F.Paste")
			(net "M_D_CPU0_SA_DQ<17>")
		)
		(pad "AK73" smd circle
			(at 22.77491 -13.337286 270)
			(size 0.4318 0.4318)
			(layers "F.Cu" "F.Mask" "F.Paste")
			(net "GND")
		)
		(pad "AK75" smd circle
			(at 24.402796 -13.337286 270)
			(size 0.4318 0.4318)
			(layers "F.Cu" "F.Mask" "F.Paste")
			(net "M_D_CPU0_SA_DQ<12>")
		)
		(pad "AK77" smd circle
			(at 26.030682 -13.337286 270)
			(size 0.4318 0.4318)
			(layers "F.Cu" "F.Mask" "F.Paste")
			(net "M_D_CPU0_SA_DQ<9>")
		)
		(pad "AK79" smd circle
			(at 27.658314 -13.337286 270)
			(size 0.4318 0.4318)
			(layers "F.Cu" "F.Mask" "F.Paste")
			(net "GND")
		)
		(pad "AK81" smd circle
			(at 29.2862 -13.337286 270)
			(size 0.4318 0.4318)
			(layers "F.Cu" "F.Mask" "F.Paste")
			(net "GND")
		)
		(pad "AK83" smd circle
			(at 30.914086 -13.337286 270)
			(size 0.4318 0.4318)
			(layers "F.Cu" "F.Mask" "F.Paste")
			(net "GND")
		)
		(pad "AK85" smd circle
			(at 32.541718 -13.337286 270)
			(size 0.4318 0.4318)
			(layers "F.Cu" "F.Mask" "F.Paste")
			(net "P5E_CPU0_PE4_TX_DP<9>")
		)
		(pad "AK87" smd circle
			(at 34.169604 -13.337286 270)
			(size 0.4318 0.4318)
			(layers "F.Cu" "F.Mask" "F.Paste")
			(net "GND")
		)
		(pad "AK89" smd circle
			(at 35.797236 -13.337286 270)
			(size 0.4318 0.4318)
			(layers "F.Cu" "F.Mask" "F.Paste")
			(net "P5E_CPU0_PE4_RX_DN<9>")
		)
		(pad "AK91" smd oval
			(at 37.425122 -13.337286)
			(size 0.381 0.4826)
			(drill
				(offset 0 -0.0508)
			)
			(layers "F.Cu" "F.Mask" "F.Paste")
			(net "GND")
		)
		(pad "AL1" smd oval
			(at -37.425122 -12.977114 180)
			(size 0.381 0.4826)
			(drill
				(offset 0 -0.0508)
			)
			(layers "F.Cu" "F.Mask" "F.Paste")
			(net "GND")
		)
		(pad "AL3" smd circle
			(at -35.797236 -12.977114 270)
			(size 0.4318 0.4318)
			(layers "F.Cu" "F.Mask" "F.Paste")
			(net "UPI_CPU0_CPU1_P0P1_DP<11>")
		)
		(pad "AL5" smd circle
			(at -34.169604 -12.977114 270)
			(size 0.4318 0.4318)
			(layers "F.Cu" "F.Mask" "F.Paste")
			(net "GND")
		)
		(pad "AL7" smd circle
			(at -32.541718 -12.977114 270)
			(size 0.4318 0.4318)
			(layers "F.Cu" "F.Mask" "F.Paste")
			(net "UPI_CPU1_CPU0_P1P0_DN<10>")
		)
		(pad "AL9" smd circle
			(at -30.914086 -12.977114 270)
			(size 0.4318 0.4318)
			(layers "F.Cu" "F.Mask" "F.Paste")
			(net "GND")
		)
		(pad "AL11" smd circle
			(at -29.2862 -12.977114 270)
			(size 0.4318 0.4318)
			(layers "F.Cu" "F.Mask" "F.Paste")
			(net "P5E_CPU0_PE0_RX_DP<10>")
		)
		(pad "AL13" smd circle
			(at -27.658314 -12.977114 270)
			(size 0.4318 0.4318)
			(layers "F.Cu" "F.Mask" "F.Paste")
			(net "GND")
		)
		(pad "AL15" smd circle
			(at -26.030682 -12.977114 270)
			(size 0.4318 0.4318)
			(layers "F.Cu" "F.Mask" "F.Paste")
			(net "P5E_CPU0_PE0_TX_DP<9>")
		)
		(pad "AL17" smd circle
			(at -24.402796 -12.977114 270)
			(size 0.4318 0.4318)
			(layers "F.Cu" "F.Mask" "F.Paste")
			(net "GND")
		)
		(pad "AL19" smd circle
			(at -22.77491 -12.977114 270)
			(size 0.4318 0.4318)
			(layers "F.Cu" "F.Mask" "F.Paste")
			(net "M_D_CPU0_SB_DQ<29>")
		)
		(pad "AL21" smd circle
			(at -21.147278 -12.977114 270)
			(size 0.4318 0.4318)
			(layers "F.Cu" "F.Mask" "F.Paste")
			(net "M_D_CPU0_SB_DQS_DP<3>")
		)
		(pad "AL23" smd circle
			(at -19.519392 -12.977114 270)
			(size 0.4318 0.4318)
			(layers "F.Cu" "F.Mask" "F.Paste")
			(net "M_D_CPU0_SB_DQ<24>")
		)
		(pad "AL25" smd circle
			(at -17.89176 -12.977114 270)
			(size 0.4318 0.4318)
			(layers "F.Cu" "F.Mask" "F.Paste")
			(net "M_D_CPU0_SB_DQ<13>")
		)
		(pad "AL27" smd circle
			(at -16.263874 -12.977114 270)
			(size 0.4318 0.4318)
			(layers "F.Cu" "F.Mask" "F.Paste")
			(net "M_D_CPU0_SB_DQS_DP<1>")
		)
		(pad "AL29" smd circle
			(at -14.635988 -12.977114 270)
			(size 0.4318 0.4318)
			(layers "F.Cu" "F.Mask" "F.Paste")
			(net "M_D_CPU0_SB_DQ<8>")
		)
		(pad "AL31" smd circle
			(at -13.008356 -12.977114 270)
			(size 0.4318 0.4318)
			(layers "F.Cu" "F.Mask" "F.Paste")
			(net "M_D_CPU0_SB_DQ<5>")
		)
		(pad "AL33" smd circle
			(at -11.380724 -12.977114 270)
			(size 0.4318 0.4318)
			(layers "F.Cu" "F.Mask" "F.Paste")
			(net "M_D_CPU0_SB_DQS_DP<0>")
		)
		(pad "AL35" smd circle
			(at -9.752838 -12.977114 270)
			(size 0.4318 0.4318)
			(layers "F.Cu" "F.Mask" "F.Paste")
			(net "M_D_CPU0_SB_DQ<0>")
		)
		(pad "AL37" smd circle
			(at -8.124952 -12.977114 270)
			(size 0.4318 0.4318)
			(layers "F.Cu" "F.Mask" "F.Paste")
			(net "M_D_CPU0_SB_CB<1>")
		)
		(pad "AL39" smd circle
			(at -6.49732 -12.977114 270)
			(size 0.4318 0.4318)
			(layers "F.Cu" "F.Mask" "F.Paste")
			(net "M_D_CPU0_SB_DQS_DP<9>")
		)
		(pad "AL41" smd circle
			(at -4.869434 -12.977114 270)
			(size 0.4318 0.4318)
			(layers "F.Cu" "F.Mask" "F.Paste")
			(net "M_D_CPU0_SB_CB<4>")
		)
		(pad "AL43" smd circle
			(at -3.241802 -12.977114 270)
			(size 0.4318 0.4318)
			(layers "F.Cu" "F.Mask" "F.Paste")
			(net "M_D_CPU0_SB_CA<1>")
		)
		(pad "AL45" smd circle
			(at -1.613916 -12.977114 270)
			(size 0.4318 0.4318)
			(layers "F.Cu" "F.Mask" "F.Paste")
			(net "M_D_CPU0_CLK_DP<0>")
		)
		(pad "AL48" smd circle
			(at 2.427732 -12.867132 270)
			(size 0.4318 0.4318)
			(layers "F.Cu" "F.Mask" "F.Paste")
			(net "M_B_CPU0_SA_RSP<0>")
		)
		(pad "AL50" smd circle
			(at 4.055618 -12.867132 270)
			(size 0.4318 0.4318)
			(layers "F.Cu" "F.Mask" "F.Paste")
			(net "M_D_CPU0_SA_CA<4>")
		)
		(pad "AL52" smd circle
			(at 5.68325 -12.867132 270)
			(size 0.4318 0.4318)
			(layers "F.Cu" "F.Mask" "F.Paste")
			(net "GND")
		)
		(pad "AL54" smd circle
			(at 7.311136 -12.867132 270)
			(size 0.4318 0.4318)
			(layers "F.Cu" "F.Mask" "F.Paste")
			(net "M_D_CPU0_SA_CS_N<0>")
		)
		(pad "AL56" smd circle
			(at 8.939022 -12.867132 270)
			(size 0.4318 0.4318)
			(layers "F.Cu" "F.Mask" "F.Paste")
			(net "M_D_CPU0_SA_CB<5>")
		)
		(pad "AL58" smd circle
			(at 10.566654 -12.867132 270)
			(size 0.4318 0.4318)
			(layers "F.Cu" "F.Mask" "F.Paste")
			(net "M_D_CPU0_SA_DQS_DP<4>")
		)
		(pad "AL60" smd circle
			(at 12.19454 -12.867132 270)
			(size 0.4318 0.4318)
			(layers "F.Cu" "F.Mask" "F.Paste")
			(net "M_D_CPU0_SA_CB<0>")
		)
		(pad "AL62" smd circle
			(at 13.822426 -12.867132 270)
			(size 0.4318 0.4318)
			(layers "F.Cu" "F.Mask" "F.Paste")
			(net "M_D_CPU0_SA_DQ<29>")
		)
		(pad "AL64" smd circle
			(at 15.450058 -12.867132 270)
			(size 0.4318 0.4318)
			(layers "F.Cu" "F.Mask" "F.Paste")
			(net "M_D_CPU0_SA_DQS_DP<3>")
		)
		(pad "AL66" smd circle
			(at 17.07769 -12.867132 270)
			(size 0.4318 0.4318)
			(layers "F.Cu" "F.Mask" "F.Paste")
			(net "M_D_CPU0_SA_DQ<24>")
		)
		(pad "AL68" smd circle
			(at 18.705576 -12.867132 270)
			(size 0.4318 0.4318)
			(layers "F.Cu" "F.Mask" "F.Paste")
			(net "M_D_CPU0_SA_DQ<21>")
		)
		(pad "AL70" smd circle
			(at 20.333462 -12.867132 270)
			(size 0.4318 0.4318)
			(layers "F.Cu" "F.Mask" "F.Paste")
			(net "M_D_CPU0_SA_DQS_DP<2>")
		)
		(pad "AL72" smd circle
			(at 21.961094 -12.867132 270)
			(size 0.4318 0.4318)
			(layers "F.Cu" "F.Mask" "F.Paste")
			(net "M_D_CPU0_SA_DQ<16>")
		)
		(pad "AL74" smd circle
			(at 23.58898 -12.867132 270)
			(size 0.4318 0.4318)
			(layers "F.Cu" "F.Mask" "F.Paste")
			(net "M_D_CPU0_SA_DQ<13>")
		)
		(pad "AL76" smd circle
			(at 25.216612 -12.867132 270)
			(size 0.4318 0.4318)
			(layers "F.Cu" "F.Mask" "F.Paste")
			(net "M_D_CPU0_SA_DQS_DP<1>")
		)
		(pad "AL78" smd circle
			(at 26.844498 -12.867132 270)
			(size 0.4318 0.4318)
			(layers "F.Cu" "F.Mask" "F.Paste")
			(net "M_D_CPU0_SA_DQ<8>")
		)
		(pad "AL80" smd circle
			(at 28.472384 -12.867132 270)
			(size 0.4318 0.4318)
			(layers "F.Cu" "F.Mask" "F.Paste")
			(net "GND")
		)
		(pad "AL82" smd circle
			(at 30.100016 -12.867132 270)
			(size 0.4318 0.4318)
			(layers "F.Cu" "F.Mask" "F.Paste")
			(net "GND")
		)
		(pad "AL84" smd circle
			(at 31.727902 -12.867132 270)
			(size 0.4318 0.4318)
			(layers "F.Cu" "F.Mask" "F.Paste")
			(net "GND")
		)
		(pad "AL86" smd circle
			(at 33.355534 -12.867132 270)
			(size 0.4318 0.4318)
			(layers "F.Cu" "F.Mask" "F.Paste")
			(net "P5E_CPU0_PE4_TX_DN<10>")
		)
		(pad "AL88" smd circle
			(at 34.98342 -12.867132 270)
			(size 0.4318 0.4318)
			(layers "F.Cu" "F.Mask" "F.Paste")
			(net "GND")
		)
		(pad "AL90" smd circle
			(at 36.611306 -12.867132 270)
			(size 0.4318 0.4318)
			(layers "F.Cu" "F.Mask" "F.Paste")
			(net "P5E_CPU0_PE4_RX_DP<10>")
		)
		(pad "AM2" smd circle
			(at -36.611306 -12.507468 270)
			(size 0.4318 0.4318)
			(layers "F.Cu" "F.Mask" "F.Paste")
			(net "UPI_CPU0_CPU1_P0P1_DN<11>")
		)
		(pad "AM4" smd circle
			(at -34.98342 -12.507468 270)
			(size 0.4318 0.4318)
			(layers "F.Cu" "F.Mask" "F.Paste")
			(net "GND")
		)
		(pad "AM6" smd circle
			(at -33.355534 -12.507468 270)
			(size 0.4318 0.4318)
			(layers "F.Cu" "F.Mask" "F.Paste")
			(net "UPI_CPU1_CPU0_P1P0_DN<11>")
		)
		(pad "AM8" smd circle
			(at -31.727902 -12.507468 270)
			(size 0.4318 0.4318)
			(layers "F.Cu" "F.Mask" "F.Paste")
			(net "GND")
		)
		(pad "AM10" smd circle
			(at -30.100016 -12.507468 270)
			(size 0.4318 0.4318)
			(layers "F.Cu" "F.Mask" "F.Paste")
			(net "P5E_CPU0_PE0_RX_DN<11>")
		)
		(pad "AM12" smd circle
			(at -28.472384 -12.507468 270)
			(size 0.4318 0.4318)
			(layers "F.Cu" "F.Mask" "F.Paste")
			(net "GND")
		)
		(pad "AM14" smd circle
			(at -26.844498 -12.507468 270)
			(size 0.4318 0.4318)
			(layers "F.Cu" "F.Mask" "F.Paste")
			(net "P5E_CPU0_PE0_TX_DP<10>")
		)
		(pad "AM16" smd circle
			(at -25.216612 -12.507468 270)
			(size 0.4318 0.4318)
			(layers "F.Cu" "F.Mask" "F.Paste")
			(net "GND")
		)
		(pad "AM18" smd circle
			(at -23.58898 -12.507468 270)
			(size 0.4318 0.4318)
			(layers "F.Cu" "F.Mask" "F.Paste")
			(net "GND")
		)
		(pad "AM20" smd circle
			(at -21.961094 -12.507468 270)
			(size 0.4318 0.4318)
			(layers "F.Cu" "F.Mask" "F.Paste")
			(net "GND")
		)
		(pad "AM22" smd circle
			(at -20.333462 -12.507468 270)
			(size 0.4318 0.4318)
			(layers "F.Cu" "F.Mask" "F.Paste")
			(net "GND")
		)
		(pad "AM24" smd circle
			(at -18.705576 -12.507468 270)
			(size 0.4318 0.4318)
			(layers "F.Cu" "F.Mask" "F.Paste")
			(net "GND")
		)
	)
)
